FILE_TYPE=LIBRARY_PARTS;
primitive 'PCA9617','PCA9617_SSOP';
  pin
    'EN':
      PIN_NUMBER='(5)';
      INPUT_LOAD='(-0.01,0.01)';
    'SCLA':
      PIN_NUMBER='(2)';
      INPUT_LOAD='(-0.01,0.01)';
    'SCLB':
      PIN_NUMBER='(7)';
      OUTPUT_LOAD='(1.0,-1.0)';
    'SDAA':
      PIN_NUMBER='(3)';
      INPUT_LOAD='(-0.01,0.01)';
    'SDAB':
      PIN_NUMBER='(6)';
      OUTPUT_LOAD='(1.0,-1.0)';
    'VCCA':
      PIN_NUMBER='(1)';
      PIN_TYPE='POWER';
      NO_LOAD_CHECK='BOTH';
      NO_IO_CHECK='BOTH';
      ALLOW_CONNECT='TRUE';
    'VCCB':
      PIN_NUMBER='(8)';
      PIN_TYPE='POWER';
      NO_LOAD_CHECK='BOTH';
      NO_IO_CHECK='BOTH';
      ALLOW_CONNECT='TRUE';
  end_pin;
  body
    POWER_PINS='(GND:4)';
    PART_NAME='PCA9617';
    PHYS_DES_PREFIX='U';
  end_body;
end_primitive;
END.
